(kicad_pcb
	(version 20260206)
	(generator "pcbnew")
	(generator_version "10.0")
	(general
		(thickness 1.6)
		(legacy_teardrops no)
	)
	(paper "A4")
	(title_block
		(title "03242023_DA0F0TMBIJ0_F0T_Motherboard_J_brd_V01_OCP.brd")
		(comment 1 "Grand Teton / footprints 1244-1249 of 6105")
	)
	(layers
		(0 "F.Cu" signal "TOP")
		(4 "In1.Cu" signal "GND")
		(6 "In2.Cu" signal "IN1")
		(8 "In3.Cu" signal "GND1")
		(10 "In4.Cu" signal "IN2")
		(12 "In5.Cu" signal "GND2")
		(14 "In6.Cu" signal "IN3")
		(16 "In7.Cu" signal "GND3")
		(18 "In8.Cu" signal "VCC")
		(20 "In9.Cu" signal "VCC1")
		(22 "In10.Cu" signal "GND4")
		(24 "In11.Cu" signal "IN4")
		(26 "In12.Cu" signal "GND5")
		(28 "In13.Cu" signal "IN5")
		(30 "In14.Cu" signal "GND6")
		(32 "In15.Cu" signal "IN6")
		(34 "In16.Cu" signal "GND7")
		(2 "B.Cu" signal "BOTTOM")
		(9 "F.Adhes" user "F.Adhesive")
		(11 "B.Adhes" user "B.Adhesive")
		(13 "F.Paste" user "Package Geometry/Pastemask Top")
		(15 "B.Paste" user "Package Geometry/Pastemask Bottom")
		(5 "F.SilkS" user "Ref Des/Silkscreen Top")
		(7 "B.SilkS" user "Ref Des/Silkscreen Bottom")
		(1 "F.Mask" user "Board Geometry/Soldermask Top")
		(3 "B.Mask" user "Board Geometry/Soldermask Bottom")
		(17 "Dwgs.User" user "User.Drawings")
		(19 "Cmts.User" user "User.Comments")
		(21 "Eco1.User" user "User.Eco1")
		(23 "Eco2.User" user "User.Eco2")
		(25 "Edge.Cuts" user "Board Geometry/Outline")
		(27 "Margin" user)
		(31 "F.CrtYd" user "Package Geometry/Place Bound Top")
		(29 "B.CrtYd" user "Package Geometry/Place Bound Bottom")
		(35 "F.Fab" user "Ref Des/Assembly Top")
		(33 "B.Fab" user "Ref Des/Assembly Bottom")
	)
	(footprint ""
		(layer "F.Cu")
		(at 361.44454 -412.9913 180)
		(property "Reference" "Q154"
			(at -1.8923 -2.470912 0)
			(unlocked yes)
			(layer "F.SilkS")
			(effects
				(font
					(size 0.7874 0.5842)
					(thickness 0.1524)
				)
				(justify left)
			)
		)
		(property "Value" ""
			(at 0 0 180)
			(layer "F.Fab")
			(effects
				(font
					(size 1.27 1.27)
				)
			)
		)
		(duplicate_pad_numbers_are_jumpers no)
		(fp_line
			(start 1.332738 1.100074)
			(end -1.332738 1.100074)
			(stroke
				(width 0.1524)
				(type default)
			)
			(layer "F.SilkS")
		)
		(fp_line
			(start 1.332738 -1.100074)
			(end 1.332738 1.100074)
			(stroke
				(width 0.1524)
				(type default)
			)
			(layer "F.SilkS")
		)
		(fp_line
			(start 0.4826 -1.100074)
			(end 1.332738 -1.100074)
			(stroke
				(width 0.1524)
				(type default)
			)
			(layer "F.SilkS")
		)
		(fp_line
			(start 0 -0.541274)
			(end 0.4826 -1.100074)
			(stroke
				(width 0.1524)
				(type default)
			)
			(layer "F.SilkS")
		)
		(fp_line
			(start -0.4826 -1.100074)
			(end 0 -0.541274)
			(stroke
				(width 0.1524)
				(type default)
			)
			(layer "F.SilkS")
		)
		(fp_line
			(start -1.332738 1.100074)
			(end -1.332738 -1.100074)
			(stroke
				(width 0.1524)
				(type default)
			)
			(layer "F.SilkS")
		)
		(fp_line
			(start -1.332738 -1.100074)
			(end -0.4826 -1.100074)
			(stroke
				(width 0.1524)
				(type default)
			)
			(layer "F.SilkS")
		)
		(fp_poly
			(pts
				(xy -2.422398 -1.07442) (xy -1.925828 -1.570736) (xy -1.67767 -0.826008)
			)
			(stroke
				(width 0)
				(type default)
			)
			(fill yes)
			(layer "F.SilkS")
		)
		(fp_line
			(start 0.674878 1.100074)
			(end -0.674878 1.100074)
			(stroke
				(width 0.1)
				(type default)
			)
			(layer "F.Fab")
		)
		(fp_line
			(start 0.674878 -1.100074)
			(end 0.674878 1.100074)
			(stroke
				(width 0.1)
				(type default)
			)
			(layer "F.Fab")
		)
		(fp_line
			(start -0.674878 1.100074)
			(end -0.674878 -1.100074)
			(stroke
				(width 0.1)
				(type default)
			)
			(layer "F.Fab")
		)
		(fp_line
			(start -0.674878 -1.100074)
			(end 0.674878 -1.100074)
			(stroke
				(width 0.1)
				(type default)
			)
			(layer "F.Fab")
		)
		(fp_poly
			(pts
				(xy -2.2352 -0.298958) (xy -2.2352 -1.001014) (xy -1.533144 -0.649986)
			)
			(stroke
				(width 0)
				(type default)
			)
			(fill yes)
			(layer "F.Fab")
		)
		(pad "1" smd rect
			(at -0.94996 -0.649986 270)
			(size 0.4318 0.508)
			(layers "F.Cu" "F.Mask" "F.Paste")
			(net "GND")
		)
		(pad "2" smd rect
			(at -0.94996 0 270)
			(size 0.4318 0.508)
			(layers "F.Cu" "F.Mask" "F.Paste")
			(net "PRSNT_CABLE_GPU_A3_N")
		)
		(pad "3" smd rect
			(at -0.94996 0.649986 270)
			(size 0.4318 0.508)
			(layers "F.Cu" "F.Mask" "F.Paste")
			(net "PRSNT_CABLE_GPU_A3_ISO_N")
		)
		(pad "4" smd rect
			(at 0.94996 0.649986 270)
			(size 0.4318 0.508)
			(layers "F.Cu" "F.Mask" "F.Paste")
			(net "GND")
		)
		(pad "5" smd rect
			(at 0.94996 0 270)
			(size 0.4318 0.508)
			(layers "F.Cu" "F.Mask" "F.Paste")
			(net "PRSNT_CABLE_GPU_A3")
		)
		(pad "6" smd rect
			(at 0.94996 -0.649986 270)
			(size 0.4318 0.508)
			(layers "F.Cu" "F.Mask" "F.Paste")
			(net "PRSNT_CABLE_GPU_A3")
		)
	)
	(footprint ""
		(layer "F.Cu")
		(at 457.684632 -107.018836)
		(property "Reference" "U211"
			(at -1.4732 -1.768348 0)
			(unlocked yes)
			(layer "F.SilkS")
			(effects
				(font
					(size 0.7874 0.5842)
					(thickness 0.1524)
				)
				(justify left)
			)
		)
		(property "Value" ""
			(at 0 0 0)
			(layer "F.Fab")
			(effects
				(font
					(size 1.27 1.27)
				)
			)
		)
		(duplicate_pad_numbers_are_jumpers no)
		(fp_line
			(start -1.38176 -1.100074)
			(end -1.38176 1.100074)
			(stroke
				(width 0.1524)
				(type default)
			)
			(layer "F.SilkS")
		)
		(fp_line
			(start -1.38176 1.100074)
			(end 1.38176 1.100074)
			(stroke
				(width 0.1524)
				(type default)
			)
			(layer "F.SilkS")
		)
		(fp_line
			(start -0.592074 -1.100074)
			(end -1.38176 -1.100074)
			(stroke
				(width 0.1524)
				(type default)
			)
			(layer "F.SilkS")
		)
		(fp_line
			(start 0 -0.508)
			(end -0.592074 -1.100074)
			(stroke
				(width 0.1524)
				(type default)
			)
			(layer "F.SilkS")
		)
		(fp_line
			(start 0.592074 -1.100074)
			(end 0 -0.508)
			(stroke
				(width 0.1524)
				(type default)
			)
			(layer "F.SilkS")
		)
		(fp_line
			(start 1.38176 -1.100074)
			(end 0.592074 -1.100074)
			(stroke
				(width 0.1524)
				(type default)
			)
			(layer "F.SilkS")
		)
		(fp_line
			(start 1.38176 1.100074)
			(end 1.38176 -1.100074)
			(stroke
				(width 0.1524)
				(type default)
			)
			(layer "F.SilkS")
		)
		(fp_poly
			(pts
				(xy -1.50241 -0.649986) (xy -1.9431 -0.429768) (xy -1.9431 -0.870204)
			)
			(stroke
				(width 0)
				(type default)
			)
			(fill yes)
			(layer "F.SilkS")
		)
		(fp_line
			(start -0.674878 -1.100074)
			(end -0.674878 1.100074)
			(stroke
				(width 0.1)
				(type default)
			)
			(layer "F.Fab")
		)
		(fp_line
			(start -0.674878 1.100074)
			(end 0.674878 1.100074)
			(stroke
				(width 0.1)
				(type default)
			)
			(layer "F.Fab")
		)
		(fp_line
			(start 0.674878 -1.100074)
			(end -0.674878 -1.100074)
			(stroke
				(width 0.1)
				(type default)
			)
			(layer "F.Fab")
		)
		(fp_line
			(start 0.674878 1.100074)
			(end 0.674878 -1.100074)
			(stroke
				(width 0.1)
				(type default)
			)
			(layer "F.Fab")
		)
		(fp_poly
			(pts
				(xy -1.9431 -0.870204) (xy -1.50241 -0.649986) (xy -1.9431 -0.429768)
			)
			(stroke
				(width 0)
				(type default)
			)
			(fill yes)
			(layer "F.Fab")
		)
		(pad "1" smd rect
			(at -0.94996 -0.649986 270)
			(size 0.4318 0.6096)
			(layers "F.Cu" "F.Mask" "F.Paste")
			(net "OCP_SFF_PRSNT0_R_N")
		)
		(pad "2" smd rect
			(at -0.94996 0 270)
			(size 0.4318 0.6096)
			(layers "F.Cu" "F.Mask" "F.Paste")
			(net "GND")
		)
		(pad "3" smd rect
			(at -0.94996 0.649986 270)
			(size 0.4318 0.6096)
			(layers "F.Cu" "F.Mask" "F.Paste")
			(net "OCP_SFF_PRSNT1_R_N")
		)
		(pad "4" smd rect
			(at 0.94996 0.649986 270)
			(size 0.4318 0.6096)
			(layers "F.Cu" "F.Mask" "F.Paste")
			(net "HP_LVC3_OCP_V3_1_PRSNT2_N_R")
		)
		(pad "5" smd rect
			(at 0.94996 0 270)
			(size 0.4318 0.6096)
			(layers "F.Cu" "F.Mask" "F.Paste")
			(net "P3V3_AUX")
		)
		(pad "6" smd rect
			(at 0.94996 -0.649986 270)
			(size 0.4318 0.6096)
			(layers "F.Cu" "F.Mask" "F.Paste")
			(net "HP_LVC3_OCP_V3_1_PRSNT2_N_R")
		)
	)
	(footprint ""
		(layer "F.Cu")
		(at 360.553 -415.889948)
		(property "Reference" "Q146"
			(at -1.4224 -1.768348 0)
			(unlocked yes)
			(layer "F.SilkS")
			(effects
				(font
					(size 0.7874 0.5842)
					(thickness 0.1524)
				)
				(justify left)
			)
		)
		(property "Value" ""
			(at 0 0 0)
			(layer "F.Fab")
			(effects
				(font
					(size 1.27 1.27)
				)
			)
		)
		(duplicate_pad_numbers_are_jumpers no)
		(fp_line
			(start -1.332738 -1.100074)
			(end -0.4826 -1.100074)
			(stroke
				(width 0.1524)
				(type default)
			)
			(layer "F.SilkS")
		)
		(fp_line
			(start -1.332738 1.100074)
			(end -1.332738 -1.100074)
			(stroke
				(width 0.1524)
				(type default)
			)
			(layer "F.SilkS")
		)
		(fp_line
			(start -0.4826 -1.100074)
			(end 0 -0.541274)
			(stroke
				(width 0.1524)
				(type default)
			)
			(layer "F.SilkS")
		)
		(fp_line
			(start 0 -0.541274)
			(end 0.4826 -1.100074)
			(stroke
				(width 0.1524)
				(type default)
			)
			(layer "F.SilkS")
		)
		(fp_line
			(start 0.4826 -1.100074)
			(end 1.332738 -1.100074)
			(stroke
				(width 0.1524)
				(type default)
			)
			(layer "F.SilkS")
		)
		(fp_line
			(start 1.332738 -1.100074)
			(end 1.332738 1.100074)
			(stroke
				(width 0.1524)
				(type default)
			)
			(layer "F.SilkS")
		)
		(fp_line
			(start 1.332738 1.100074)
			(end -1.332738 1.100074)
			(stroke
				(width 0.1524)
				(type default)
			)
			(layer "F.SilkS")
		)
		(fp_poly
			(pts
				(xy -2.2352 -0.298958) (xy -2.2352 -1.001014) (xy -1.533144 -0.649986)
			)
			(stroke
				(width 0)
				(type default)
			)
			(fill yes)
			(layer "F.SilkS")
		)
		(fp_line
			(start -0.674878 -1.100074)
			(end 0.674878 -1.100074)
			(stroke
				(width 0.1)
				(type default)
			)
			(layer "F.Fab")
		)
		(fp_line
			(start -0.674878 1.100074)
			(end -0.674878 -1.100074)
			(stroke
				(width 0.1)
				(type default)
			)
			(layer "F.Fab")
		)
		(fp_line
			(start 0.674878 -1.100074)
			(end 0.674878 1.100074)
			(stroke
				(width 0.1)
				(type default)
			)
			(layer "F.Fab")
		)
		(fp_line
			(start 0.674878 1.100074)
			(end -0.674878 1.100074)
			(stroke
				(width 0.1)
				(type default)
			)
			(layer "F.Fab")
		)
		(fp_poly
			(pts
				(xy -2.2352 -0.298958) (xy -2.2352 -1.001014) (xy -1.533144 -0.649986)
			)
			(stroke
				(width 0)
				(type default)
			)
			(fill yes)
			(layer "F.Fab")
		)
		(pad "1" smd rect
			(at -0.94996 -0.649986 90)
			(size 0.4318 0.508)
			(layers "F.Cu" "F.Mask" "F.Paste")
			(net "GND")
		)
		(pad "2" smd rect
			(at -0.94996 0 90)
			(size 0.4318 0.508)
			(layers "F.Cu" "F.Mask" "F.Paste")
			(net "SWB_HSC_PWRGD")
		)
		(pad "3" smd rect
			(at -0.94996 0.649986 90)
			(size 0.4318 0.508)
			(layers "F.Cu" "F.Mask" "F.Paste")
			(net "SWB_HSC_PWRGD_ISO")
		)
		(pad "4" smd rect
			(at 0.94996 0.649986 90)
			(size 0.4318 0.508)
			(layers "F.Cu" "F.Mask" "F.Paste")
			(net "GND")
		)
		(pad "5" smd rect
			(at 0.94996 0 90)
			(size 0.4318 0.508)
			(layers "F.Cu" "F.Mask" "F.Paste")
			(net "SWB_HSC_PWRGD_N")
		)
		(pad "6" smd rect
			(at 0.94996 -0.649986 90)
			(size 0.4318 0.508)
			(layers "F.Cu" "F.Mask" "F.Paste")
			(net "SWB_HSC_PWRGD_N")
		)
	)
	(footprint ""
		(layer "F.Cu")
		(at 424.204892 -385.282948)
		(property "Reference" "R2934"
			(at 0 0 0)
			(layer "F.SilkS")
			(hide yes)
			(effects
				(font
					(size 1.27 1.27)
				)
			)
		)
		(property "Value" ""
			(at 0 0 0)
			(layer "F.Fab")
			(effects
				(font
					(size 1.27 1.27)
				)
			)
		)
		(duplicate_pad_numbers_are_jumpers no)
		(fp_line
			(start -0.7874 -0.4064)
			(end 0.7874 -0.4064)
			(stroke
				(width 0.1524)
				(type default)
			)
			(layer "F.SilkS")
		)
		(fp_line
			(start -0.7874 0.4064)
			(end -0.7874 -0.4064)
			(stroke
				(width 0.1524)
				(type default)
			)
			(layer "F.SilkS")
		)
		(fp_line
			(start 0.7874 -0.4064)
			(end 0.7874 0.4064)
			(stroke
				(width 0.1524)
				(type default)
			)
			(layer "F.SilkS")
		)
		(fp_line
			(start 0.7874 0.4064)
			(end -0.7874 0.4064)
			(stroke
				(width 0.1524)
				(type default)
			)
			(layer "F.SilkS")
		)
		(fp_line
			(start -0.67945 -0.305054)
			(end -0.12065 -0.305054)
			(stroke
				(width 0.1)
				(type default)
			)
			(layer "F.Fab")
		)
		(fp_line
			(start -0.67945 0.3048)
			(end -0.67945 -0.305054)
			(stroke
				(width 0.1)
				(type default)
			)
			(layer "F.Fab")
		)
		(fp_line
			(start -0.12065 -0.305054)
			(end -0.12065 -0.2794)
			(stroke
				(width 0.1)
				(type default)
			)
			(layer "F.Fab")
		)
		(fp_line
			(start -0.12065 -0.2794)
			(end 0.12065 -0.2794)
			(stroke
				(width 0.1)
				(type default)
			)
			(layer "F.Fab")
		)
		(fp_line
			(start -0.12065 0.2794)
			(end -0.12065 0.3048)
			(stroke
				(width 0.1)
				(type default)
			)
			(layer "F.Fab")
		)
		(fp_line
			(start -0.12065 0.3048)
			(end -0.67945 0.3048)
			(stroke
				(width 0.1)
				(type default)
			)
			(layer "F.Fab")
		)
		(fp_line
			(start 0.120396 0.2794)
			(end -0.12065 0.2794)
			(stroke
				(width 0.1)
				(type default)
			)
			(layer "F.Fab")
		)
		(fp_line
			(start 0.120396 0.3048)
			(end 0.120396 0.2794)
			(stroke
				(width 0.1)
				(type default)
			)
			(layer "F.Fab")
		)
		(fp_line
			(start 0.12065 -0.3048)
			(end 0.67945 -0.3048)
			(stroke
				(width 0.1)
				(type default)
			)
			(layer "F.Fab")
		)
		(fp_line
			(start 0.12065 -0.2794)
			(end 0.12065 -0.3048)
			(stroke
				(width 0.1)
				(type default)
			)
			(layer "F.Fab")
		)
		(fp_line
			(start 0.67945 -0.3048)
			(end 0.67945 0.3048)
			(stroke
				(width 0.1)
				(type default)
			)
			(layer "F.Fab")
		)
		(fp_line
			(start 0.67945 0.3048)
			(end 0.120396 0.3048)
			(stroke
				(width 0.1)
				(type default)
			)
			(layer "F.Fab")
		)
		(pad "1" smd circle
			(at -0.40005 0)
			(size 0 0)
			(layers "F.Cu" "F.Mask" "F.Paste")
			(net "P3V3_AUX")
		)
		(pad "2" smd circle
			(at 0.40005 0)
			(size 0 0)
			(layers "F.Cu" "F.Mask" "F.Paste")
			(net "FM_SWB_PWRGD_ISO")
		)
	)
	(footprint ""
		(layer "F.Cu")
		(at 290.571936 -367.378996 -90)
		(property "Reference" "PC1178"
			(at 0 0 270)
			(layer "F.SilkS")
			(hide yes)
			(effects
				(font
					(size 1.27 1.27)
				)
			)
		)
		(property "Value" ""
			(at 0 0 270)
			(layer "F.Fab")
			(effects
				(font
					(size 1.27 1.27)
				)
			)
		)
		(duplicate_pad_numbers_are_jumpers no)
		(fp_line
			(start -0.7874 0.4064)
			(end -0.7874 -0.4064)
			(stroke
				(width 0.1524)
				(type default)
			)
			(layer "F.SilkS")
		)
		(fp_line
			(start 0.7874 0.4064)
			(end -0.7874 0.4064)
			(stroke
				(width 0.1524)
				(type default)
			)
			(layer "F.SilkS")
		)
		(fp_line
			(start -0.7874 -0.4064)
			(end 0.7874 -0.4064)
			(stroke
				(width 0.1524)
				(type default)
			)
			(layer "F.SilkS")
		)
		(fp_line
			(start 0.7874 -0.4064)
			(end 0.7874 0.4064)
			(stroke
				(width 0.1524)
				(type default)
			)
			(layer "F.SilkS")
		)
		(fp_line
			(start -0.67945 0.3048)
			(end -0.67945 -0.305054)
			(stroke
				(width 0.1)
				(type default)
			)
			(layer "F.Fab")
		)
		(fp_line
			(start -0.12065 0.3048)
			(end -0.67945 0.3048)
			(stroke
				(width 0.1)
				(type default)
			)
			(layer "F.Fab")
		)
		(fp_line
			(start 0.120396 0.3048)
			(end 0.120396 0.2794)
			(stroke
				(width 0.1)
				(type default)
			)
			(layer "F.Fab")
		)
		(fp_line
			(start 0.67945 0.3048)
			(end 0.120396 0.3048)
			(stroke
				(width 0.1)
				(type default)
			)
			(layer "F.Fab")
		)
		(fp_line
			(start -0.12065 0.2794)
			(end -0.12065 0.3048)
			(stroke
				(width 0.1)
				(type default)
			)
			(layer "F.Fab")
		)
		(fp_line
			(start 0.120396 0.2794)
			(end -0.12065 0.2794)
			(stroke
				(width 0.1)
				(type default)
			)
			(layer "F.Fab")
		)
		(fp_line
			(start -0.12065 -0.2794)
			(end 0.12065 -0.2794)
			(stroke
				(width 0.1)
				(type default)
			)
			(layer "F.Fab")
		)
		(fp_line
			(start 0.12065 -0.2794)
			(end 0.12065 -0.3048)
			(stroke
				(width 0.1)
				(type default)
			)
			(layer "F.Fab")
		)
		(fp_line
			(start 0.12065 -0.3048)
			(end 0.67945 -0.3048)
			(stroke
				(width 0.1)
				(type default)
			)
			(layer "F.Fab")
		)
		(fp_line
			(start 0.67945 -0.3048)
			(end 0.67945 0.3048)
			(stroke
				(width 0.1)
				(type default)
			)
			(layer "F.Fab")
		)
		(fp_line
			(start -0.67945 -0.305054)
			(end -0.12065 -0.305054)
			(stroke
				(width 0.1)
				(type default)
			)
			(layer "F.Fab")
		)
		(fp_line
			(start -0.12065 -0.305054)
			(end -0.12065 -0.2794)
			(stroke
				(width 0.1)
				(type default)
			)
			(layer "F.Fab")
		)
		(pad "1" smd circle
			(at -0.40005 0 270)
			(size 0 0)
			(layers "F.Cu" "F.Mask" "F.Paste")
			(net "SW_PVCCFA_EHV_FIVRA_CPU0_BOOT4_")
		)
		(pad "2" smd circle
			(at 0.40005 0 270)
			(size 0 0)
			(layers "F.Cu" "F.Mask" "F.Paste")
			(net "SW_PVCCFA_EHV_FIVRA_CPU0_BOOTR4")
		)
	)
	(footprint ""
		(layer "F.Cu")
		(at 351.189798 -359.53573 180)
		(property "Reference" "R4593"
			(at 0 0 180)
			(layer "F.SilkS")
			(hide yes)
			(effects
				(font
					(size 1.27 1.27)
				)
			)
		)
		(property "Value" ""
			(at 0 0 180)
			(layer "F.Fab")
			(effects
				(font
					(size 1.27 1.27)
				)
			)
		)
		(duplicate_pad_numbers_are_jumpers no)
		(fp_line
			(start 0.7874 0.4064)
			(end -0.7874 0.4064)
			(stroke
				(width 0.1524)
				(type default)
			)
			(layer "F.SilkS")
		)
		(fp_line
			(start 0.7874 -0.4064)
			(end 0.7874 0.4064)
			(stroke
				(width 0.1524)
				(type default)
			)
			(layer "F.SilkS")
		)
		(fp_line
			(start -0.7874 0.4064)
			(end -0.7874 -0.4064)
			(stroke
				(width 0.1524)
				(type default)
			)
			(layer "F.SilkS")
		)
		(fp_line
			(start -0.7874 -0.4064)
			(end 0.7874 -0.4064)
			(stroke
				(width 0.1524)
				(type default)
			)
			(layer "F.SilkS")
		)
		(fp_line
			(start 0.67945 0.3048)
			(end 0.120396 0.3048)
			(stroke
				(width 0.1)
				(type default)
			)
			(layer "F.Fab")
		)
		(fp_line
			(start 0.67945 -0.3048)
			(end 0.67945 0.3048)
			(stroke
				(width 0.1)
				(type default)
			)
			(layer "F.Fab")
		)
		(fp_line
			(start 0.12065 -0.2794)
			(end 0.12065 -0.3048)
			(stroke
				(width 0.1)
				(type default)
			)
			(layer "F.Fab")
		)
		(fp_line
			(start 0.12065 -0.3048)
			(end 0.67945 -0.3048)
			(stroke
				(width 0.1)
				(type default)
			)
			(layer "F.Fab")
		)
		(fp_line
			(start 0.120396 0.3048)
			(end 0.120396 0.2794)
			(stroke
				(width 0.1)
				(type default)
			)
			(layer "F.Fab")
		)
		(fp_line
			(start 0.120396 0.2794)
			(end -0.12065 0.2794)
			(stroke
				(width 0.1)
				(type default)
			)
			(layer "F.Fab")
		)
		(fp_line
			(start -0.12065 0.3048)
			(end -0.67945 0.3048)
			(stroke
				(width 0.1)
				(type default)
			)
			(layer "F.Fab")
		)
		(fp_line
			(start -0.12065 0.2794)
			(end -0.12065 0.3048)
			(stroke
				(width 0.1)
				(type default)
			)
			(layer "F.Fab")
		)
		(fp_line
			(start -0.12065 -0.2794)
			(end 0.12065 -0.2794)
			(stroke
				(width 0.1)
				(type default)
			)
			(layer "F.Fab")
		)
		(fp_line
			(start -0.12065 -0.305054)
			(end -0.12065 -0.2794)
			(stroke
				(width 0.1)
				(type default)
			)
			(layer "F.Fab")
		)
		(fp_line
			(start -0.67945 0.3048)
			(end -0.67945 -0.305054)
			(stroke
				(width 0.1)
				(type default)
			)
			(layer "F.Fab")
		)
		(fp_line
			(start -0.67945 -0.305054)
			(end -0.12065 -0.305054)
			(stroke
				(width 0.1)
				(type default)
			)
			(layer "F.Fab")
		)
		(pad "1" smd circle
			(at -0.40005 0 180)
			(size 0 0)
			(layers "F.Cu" "F.Mask" "F.Paste")
			(net "IRQ_PVCCIN_CPU0_VRHOT_R_N")
		)
		(pad "2" smd circle
			(at 0.40005 0 180)
			(size 0 0)
			(layers "F.Cu" "F.Mask" "F.Paste")
			(net "IRQ_PVCCIN_CPU0_VRHOT_N")
		)
	)
)
